(kicad_pcb
	(version 20260206)
	(generator "pcbnew")
	(generator_version "10.0")
	(general
		(thickness 1.6)
		(legacy_teardrops no)
	)
	(paper "A4")
	(title_block
		(title "Wiwynn_Tioga_Pass_MB.brd")
		(comment 1 "Tioga Pass / footprints 294-300 of 4770")
	)
	(layers
		(0 "F.Cu" signal "TOP")
		(4 "In1.Cu" signal "L2GND")
		(6 "In2.Cu" signal "L3")
		(8 "In3.Cu" signal "L4GND")
		(10 "In4.Cu" signal "L5")
		(12 "In5.Cu" signal "L6GND")
		(14 "In6.Cu" signal "L7VCC")
		(16 "In7.Cu" signal "L8VCC")
		(18 "In8.Cu" signal "L9GND")
		(20 "In9.Cu" signal "L10")
		(22 "In10.Cu" signal "L11GND")
		(24 "In11.Cu" signal "L12")
		(26 "In12.Cu" signal "L13GND")
		(2 "B.Cu" signal "BOTTOM")
		(9 "F.Adhes" user "F.Adhesive")
		(11 "B.Adhes" user "B.Adhesive")
		(13 "F.Paste" user "Package Geometry/Pastemask Top")
		(15 "B.Paste" user "Package Geometry/Pastemask Bottom")
		(5 "F.SilkS" user "Ref Des/Silkscreen Top")
		(7 "B.SilkS" user "Ref Des/Silkscreen Bottom")
		(1 "F.Mask" user "Board Geometry/Soldermask Top")
		(3 "B.Mask" user "Board Geometry/Soldermask Bottom")
		(17 "Dwgs.User" user "User.Drawings")
		(19 "Cmts.User" user "User.Comments")
		(21 "Eco1.User" user "User.Eco1")
		(23 "Eco2.User" user "User.Eco2")
		(25 "Edge.Cuts" user "Board Geometry/Outline")
		(27 "Margin" user)
		(31 "F.CrtYd" user "Package Geometry/Place Bound Top")
		(29 "B.CrtYd" user "Package Geometry/Place Bound Bottom")
		(35 "F.Fab" user "Ref Des/Assembly Top")
		(33 "B.Fab" user "Ref Des/Assembly Bottom")
	)
	(footprint ""
		(layer "F.Cu")
		(at 174.5996 -5.461 -90)
		(property "Reference" "R4G17"
			(at 0 0 270)
			(layer "F.SilkS")
			(hide yes)
			(effects
				(font
					(size 1.27 1.27)
				)
			)
		)
		(property "Value" ""
			(at 0 0 270)
			(layer "F.Fab")
			(effects
				(font
					(size 1.27 1.27)
				)
			)
		)
		(duplicate_pad_numbers_are_jumpers no)
		(fp_rect
			(start 0.2794 -0.1016)
			(end -0.2794 0.9906)
			(stroke
				(width 0)
				(type default)
			)
			(fill no)
			(layer "F.CrtYd")
		)
		(fp_line
			(start -0.2794 0.9906)
			(end 0.2794 0.9906)
			(stroke
				(width 0.1)
				(type default)
			)
			(layer "F.Fab")
		)
		(fp_line
			(start 0.2794 0.9906)
			(end 0.2794 -0.1016)
			(stroke
				(width 0.1)
				(type default)
			)
			(layer "F.Fab")
		)
		(fp_line
			(start -0.2794 -0.1016)
			(end -0.2794 0.9906)
			(stroke
				(width 0.1)
				(type default)
			)
			(layer "F.Fab")
		)
		(fp_line
			(start 0.2794 -0.1016)
			(end -0.2794 -0.1016)
			(stroke
				(width 0.1)
				(type default)
			)
			(layer "F.Fab")
		)
		(pad "1" smd rect
			(at 0 0 270)
			(size 0.508 0.508)
			(layers "F.Cu" "F.Mask" "F.Paste")
			(net "P3V3")
		)
		(pad "2" smd rect
			(at 0 0.889 270)
			(size 0.508 0.508)
			(layers "F.Cu" "F.Mask" "F.Paste")
			(net "PWRGD_PVTT_GHJ_CPU1_R")
		)
		(zone
			(layer "F.Cu")
			(hatch none 0.5)
			(connect_pads
				(clearance 0)
			)
			(min_thickness 0.25)
			(keepout
				(tracks allowed)
				(vias not_allowed)
				(pads allowed)
				(copperpour not_allowed)
				(footprints allowed)
			)
			(placement
				(enabled no)
				(sheetname "")
			)
			(fill
				(thermal_gap 0.5)
				(thermal_bridge_width 0.5)
				(island_removal_mode 0)
			)
			(polygon
				(pts
					(xy 174.3456 -5.207) (xy 174.3456 -5.715) (xy 173.9646 -5.715) (xy 173.9646 -5.207)
				)
			)
		)
		(zone
			(layer "F.Cu")
			(hatch none 0.5)
			(connect_pads
				(clearance 0)
			)
			(min_thickness 0.25)
			(keepout
				(tracks not_allowed)
				(vias allowed)
				(pads allowed)
				(copperpour not_allowed)
				(footprints allowed)
			)
			(placement
				(enabled no)
				(sheetname "")
			)
			(fill
				(thermal_gap 0.5)
				(thermal_bridge_width 0.5)
				(island_removal_mode 0)
			)
			(polygon
				(pts
					(xy 174.3456 -5.207) (xy 174.3456 -5.715) (xy 173.9646 -5.715) (xy 173.9646 -5.207)
				)
			)
		)
	)
	(footprint ""
		(layer "F.Cu")
		(at 411.80893 -134.699248 180)
		(property "Reference" "R8B2"
			(at 0 0 180)
			(layer "F.SilkS")
			(hide yes)
			(effects
				(font
					(size 1.27 1.27)
				)
			)
		)
		(property "Value" ""
			(at 0 0 180)
			(layer "F.Fab")
			(effects
				(font
					(size 1.27 1.27)
				)
			)
		)
		(duplicate_pad_numbers_are_jumpers no)
		(fp_poly
			(pts
				(xy -0.2794 -0.1016) (xy 0.2794 -0.1016) (xy 0.2794 0.9906) (xy -0.2794 0.9906)
			)
			(stroke
				(width 0)
				(type default)
			)
			(fill no)
			(layer "F.CrtYd")
		)
		(fp_line
			(start 0.2794 0.9906)
			(end 0.2794 -0.1016)
			(stroke
				(width 0.1)
				(type default)
			)
			(layer "F.Fab")
		)
		(fp_line
			(start 0.2794 -0.1016)
			(end -0.2794 -0.1016)
			(stroke
				(width 0.1)
				(type default)
			)
			(layer "F.Fab")
		)
		(fp_line
			(start -0.2794 0.9906)
			(end 0.2794 0.9906)
			(stroke
				(width 0.1)
				(type default)
			)
			(layer "F.Fab")
		)
		(fp_line
			(start -0.2794 -0.1016)
			(end -0.2794 0.9906)
			(stroke
				(width 0.1)
				(type default)
			)
			(layer "F.Fab")
		)
		(pad "1" smd rect
			(at 0 0 180)
			(size 0.508 0.508)
			(layers "F.Cu" "F.Mask" "F.Paste")
			(net "XDP_TRST_N")
		)
		(pad "2" smd rect
			(at 0 0.889 180)
			(size 0.508 0.508)
			(layers "F.Cu" "F.Mask" "F.Paste")
			(net "GND")
		)
		(zone
			(layer "F.Cu")
			(hatch none 0.5)
			(connect_pads
				(clearance 0)
			)
			(min_thickness 0.25)
			(keepout
				(tracks not_allowed)
				(vias allowed)
				(pads allowed)
				(copperpour not_allowed)
				(footprints allowed)
			)
			(placement
				(enabled no)
				(sheetname "")
			)
			(fill
				(thermal_gap 0.5)
				(thermal_bridge_width 0.5)
				(island_removal_mode 0)
			)
			(polygon
				(pts
					(xy 412.06293 -135.334248) (xy 411.55493 -135.334248) (xy 411.55493 -134.953248) (xy 412.06293 -134.953248)
				)
			)
		)
		(zone
			(layer "F.Cu")
			(hatch none 0.5)
			(connect_pads
				(clearance 0)
			)
			(min_thickness 0.25)
			(keepout
				(tracks allowed)
				(vias not_allowed)
				(pads allowed)
				(copperpour not_allowed)
				(footprints allowed)
			)
			(placement
				(enabled no)
				(sheetname "")
			)
			(fill
				(thermal_gap 0.5)
				(thermal_bridge_width 0.5)
				(island_removal_mode 0)
			)
			(polygon
				(pts
					(xy 412.06293 -134.953248) (xy 411.55493 -134.953248) (xy 411.55493 -135.334248) (xy 412.06293 -135.334248)
				)
			)
		)
	)
	(footprint ""
		(layer "F.Cu")
		(at 103.16464 -73.318116)
		(property "Reference" "C2D38"
			(at 0 0 0)
			(layer "F.SilkS")
			(hide yes)
			(effects
				(font
					(size 1.27 1.27)
				)
			)
		)
		(property "Value" ""
			(at 0 0 0)
			(layer "F.Fab")
			(effects
				(font
					(size 1.27 1.27)
				)
			)
		)
		(duplicate_pad_numbers_are_jumpers no)
		(fp_poly
			(pts
				(xy -0.4953 -0.2032) (xy 0.4953 -0.2032) (xy 0.4953 1.6002) (xy -0.4953 1.6002)
			)
			(stroke
				(width 0)
				(type default)
			)
			(fill no)
			(layer "F.CrtYd")
		)
		(fp_line
			(start -0.4953 -0.2032)
			(end 0.4953 -0.2032)
			(stroke
				(width 0.1)
				(type default)
			)
			(layer "F.Fab")
		)
		(fp_line
			(start -0.4953 1.6002)
			(end -0.4953 -0.2032)
			(stroke
				(width 0.1)
				(type default)
			)
			(layer "F.Fab")
		)
		(fp_line
			(start 0.4953 -0.2032)
			(end 0.4953 1.6002)
			(stroke
				(width 0.1)
				(type default)
			)
			(layer "F.Fab")
		)
		(fp_line
			(start 0.4953 1.6002)
			(end -0.4953 1.6002)
			(stroke
				(width 0.1)
				(type default)
			)
			(layer "F.Fab")
		)
		(pad "1" smd rect
			(at 0 0)
			(size 0.762 0.889)
			(layers "F.Cu" "F.Mask" "F.Paste")
			(net "PVCCIN_CPU1")
		)
		(pad "2" smd rect
			(at 0 1.397)
			(size 0.762 0.889)
			(layers "F.Cu" "F.Mask" "F.Paste")
			(net "GND")
		)
		(zone
			(layer "F.Cu")
			(hatch none 0.5)
			(connect_pads
				(clearance 0)
			)
			(min_thickness 0.25)
			(keepout
				(tracks not_allowed)
				(vias allowed)
				(pads allowed)
				(copperpour not_allowed)
				(footprints allowed)
			)
			(placement
				(enabled no)
				(sheetname "")
			)
			(fill
				(thermal_gap 0.5)
				(thermal_bridge_width 0.5)
				(island_removal_mode 0)
			)
			(polygon
				(pts
					(xy 102.78364 -72.873616) (xy 103.54564 -72.873616) (xy 103.54564 -72.365616) (xy 102.78364 -72.365616)
				)
			)
		)
	)
	(footprint ""
		(layer "F.Cu")
		(at 348.6658 -101.3714 90)
		(property "Reference" "C7C17"
			(at 0 0 90)
			(layer "F.SilkS")
			(hide yes)
			(effects
				(font
					(size 1.27 1.27)
				)
			)
		)
		(property "Value" ""
			(at 0 0 90)
			(layer "F.Fab")
			(effects
				(font
					(size 1.27 1.27)
				)
			)
		)
		(duplicate_pad_numbers_are_jumpers no)
		(fp_poly
			(pts
				(xy 0.3048 -0.1016) (xy 0.3048 0.9906) (xy -0.3048 0.9906) (xy -0.3048 -0.1016)
			)
			(stroke
				(width 0)
				(type default)
			)
			(fill no)
			(layer "F.CrtYd")
		)
		(fp_line
			(start 0.3048 -0.1016)
			(end -0.3048 -0.1016)
			(stroke
				(width 0.1)
				(type default)
			)
			(layer "F.Fab")
		)
		(fp_line
			(start -0.3048 -0.1016)
			(end -0.3048 0.9906)
			(stroke
				(width 0.1)
				(type default)
			)
			(layer "F.Fab")
		)
		(fp_line
			(start 0.3048 0.9906)
			(end 0.3048 -0.1016)
			(stroke
				(width 0.1)
				(type default)
			)
			(layer "F.Fab")
		)
		(fp_line
			(start -0.3048 0.9906)
			(end 0.3048 0.9906)
			(stroke
				(width 0.1)
				(type default)
			)
			(layer "F.Fab")
		)
		(pad "1" smd rect
			(at 0 0 90)
			(size 0.508 0.508)
			(layers "F.Cu" "F.Mask" "F.Paste")
			(net "VR_PVCCIO_CPU0_PH1_VCIN")
		)
		(pad "2" smd rect
			(at 0 0.889 90)
			(size 0.508 0.508)
			(layers "F.Cu" "F.Mask" "F.Paste")
			(net "GND")
		)
		(zone
			(layer "F.Cu")
			(hatch none 0.5)
			(connect_pads
				(clearance 0)
			)
			(min_thickness 0.25)
			(keepout
				(tracks allowed)
				(vias not_allowed)
				(pads allowed)
				(copperpour not_allowed)
				(footprints allowed)
			)
			(placement
				(enabled no)
				(sheetname "")
			)
			(fill
				(thermal_gap 0.5)
				(thermal_bridge_width 0.5)
				(island_removal_mode 0)
			)
			(polygon
				(pts
					(xy 348.9198 -101.1174) (xy 348.9198 -101.6254) (xy 349.3008 -101.6254) (xy 349.3008 -101.1174)
				)
			)
		)
		(zone
			(layer "F.Cu")
			(hatch none 0.5)
			(connect_pads
				(clearance 0)
			)
			(min_thickness 0.25)
			(keepout
				(tracks not_allowed)
				(vias allowed)
				(pads allowed)
				(copperpour not_allowed)
				(footprints allowed)
			)
			(placement
				(enabled no)
				(sheetname "")
			)
			(fill
				(thermal_gap 0.5)
				(thermal_bridge_width 0.5)
				(island_removal_mode 0)
			)
			(polygon
				(pts
					(xy 349.3008 -101.1174) (xy 349.3008 -101.6254) (xy 348.9198 -101.6254) (xy 348.9198 -101.1174)
				)
			)
		)
	)
	(footprint ""
		(layer "F.Cu")
		(at 316.73038 -34.936938 90)
		(property "Reference" "R6W29"
			(at -0.8382 -0.67818 90)
			(unlocked yes)
			(layer "F.SilkS")
			(effects
				(font
					(size 0.4064 0.254)
					(thickness 0.1524)
				)
				(justify left)
			)
		)
		(property "Value" ""
			(at 0 0 90)
			(layer "F.Fab")
			(effects
				(font
					(size 1.27 1.27)
				)
			)
		)
		(duplicate_pad_numbers_are_jumpers no)
		(fp_poly
			(pts
				(xy -0.2794 -0.1016) (xy 0.2794 -0.1016) (xy 0.2794 0.9906) (xy -0.2794 0.9906)
			)
			(stroke
				(width 0)
				(type default)
			)
			(fill no)
			(layer "F.CrtYd")
		)
		(fp_line
			(start 0.2794 -0.1016)
			(end -0.2794 -0.1016)
			(stroke
				(width 0.1)
				(type default)
			)
			(layer "F.Fab")
		)
		(fp_line
			(start -0.2794 -0.1016)
			(end -0.2794 0.9906)
			(stroke
				(width 0.1)
				(type default)
			)
			(layer "F.Fab")
		)
		(fp_line
			(start 0.2794 0.9906)
			(end 0.2794 -0.1016)
			(stroke
				(width 0.1)
				(type default)
			)
			(layer "F.Fab")
		)
		(fp_line
			(start -0.2794 0.9906)
			(end 0.2794 0.9906)
			(stroke
				(width 0.1)
				(type default)
			)
			(layer "F.Fab")
		)
		(pad "1" smd rect
			(at 0 0 90)
			(size 0.508 0.508)
			(layers "F.Cu" "F.Mask" "F.Paste")
			(net "PVPP_ABC")
		)
		(pad "2" smd rect
			(at 0 0.889 90)
			(size 0.508 0.508)
			(layers "F.Cu" "F.Mask" "F.Paste")
			(net "FM_ADR_COMPLETE_CPU1_N")
		)
		(zone
			(layer "F.Cu")
			(hatch none 0.5)
			(connect_pads
				(clearance 0)
			)
			(min_thickness 0.25)
			(keepout
				(tracks allowed)
				(vias not_allowed)
				(pads allowed)
				(copperpour not_allowed)
				(footprints allowed)
			)
			(placement
				(enabled no)
				(sheetname "")
			)
			(fill
				(thermal_gap 0.5)
				(thermal_bridge_width 0.5)
				(island_removal_mode 0)
			)
			(polygon
				(pts
					(xy 316.98438 -34.682938) (xy 316.98438 -35.190938) (xy 317.36538 -35.190938) (xy 317.36538 -34.682938)
				)
			)
		)
		(zone
			(layer "F.Cu")
			(hatch none 0.5)
			(connect_pads
				(clearance 0)
			)
			(min_thickness 0.25)
			(keepout
				(tracks not_allowed)
				(vias allowed)
				(pads allowed)
				(copperpour not_allowed)
				(footprints allowed)
			)
			(placement
				(enabled no)
				(sheetname "")
			)
			(fill
				(thermal_gap 0.5)
				(thermal_bridge_width 0.5)
				(island_removal_mode 0)
			)
			(polygon
				(pts
					(xy 317.36538 -34.682938) (xy 317.36538 -35.190938) (xy 316.98438 -35.190938) (xy 316.98438 -34.682938)
				)
			)
		)
	)
	(footprint ""
		(layer "F.Cu")
		(at 182.3466 -79.4258)
		(property "Reference" "R4D27"
			(at 0 0 0)
			(layer "F.SilkS")
			(hide yes)
			(effects
				(font
					(size 1.27 1.27)
				)
			)
		)
		(property "Value" ""
			(at 0 0 0)
			(layer "F.Fab")
			(effects
				(font
					(size 1.27 1.27)
				)
			)
		)
		(duplicate_pad_numbers_are_jumpers no)
		(fp_rect
			(start -0.2794 -0.1016)
			(end 0.2794 0.9906)
			(stroke
				(width 0)
				(type default)
			)
			(fill no)
			(layer "F.CrtYd")
		)
		(fp_line
			(start -0.2794 -0.1016)
			(end -0.2794 0.9906)
			(stroke
				(width 0.1)
				(type default)
			)
			(layer "F.Fab")
		)
		(fp_line
			(start -0.2794 0.9906)
			(end 0.2794 0.9906)
			(stroke
				(width 0.1)
				(type default)
			)
			(layer "F.Fab")
		)
		(fp_line
			(start 0.2794 -0.1016)
			(end -0.2794 -0.1016)
			(stroke
				(width 0.1)
				(type default)
			)
			(layer "F.Fab")
		)
		(fp_line
			(start 0.2794 0.9906)
			(end 0.2794 -0.1016)
			(stroke
				(width 0.1)
				(type default)
			)
			(layer "F.Fab")
		)
		(pad "1" smd rect
			(at 0 0)
			(size 0.508 0.508)
			(layers "F.Cu" "F.Mask" "F.Paste")
			(net "VR_FET_SW_P12V_STBY_PVCCIN_CPU0")
		)
		(pad "2" smd rect
			(at 0 0.889)
			(size 0.508 0.508)
			(layers "F.Cu" "F.Mask" "F.Paste")
			(net "VR_PVCCIN_CPU0_AVINSEN")
		)
		(zone
			(layer "F.Cu")
			(hatch none 0.5)
			(connect_pads
				(clearance 0)
			)
			(min_thickness 0.25)
			(keepout
				(tracks allowed)
				(vias not_allowed)
				(pads allowed)
				(copperpour not_allowed)
				(footprints allowed)
			)
			(placement
				(enabled no)
				(sheetname "")
			)
			(fill
				(thermal_gap 0.5)
				(thermal_bridge_width 0.5)
				(island_removal_mode 0)
			)
			(polygon
				(pts
					(xy 182.0926 -79.1718) (xy 182.0926 -78.7908) (xy 182.6006 -78.7908) (xy 182.6006 -79.1718)
				)
			)
		)
		(zone
			(layer "F.Cu")
			(hatch none 0.5)
			(connect_pads
				(clearance 0)
			)
			(min_thickness 0.25)
			(keepout
				(tracks not_allowed)
				(vias allowed)
				(pads allowed)
				(copperpour not_allowed)
				(footprints allowed)
			)
			(placement
				(enabled no)
				(sheetname "")
			)
			(fill
				(thermal_gap 0.5)
				(thermal_bridge_width 0.5)
				(island_removal_mode 0)
			)
			(polygon
				(pts
					(xy 182.0926 -79.1718) (xy 182.0926 -78.7908) (xy 182.6006 -78.7908) (xy 182.6006 -79.1718)
				)
			)
		)
	)
	(footprint ""
		(layer "F.Cu")
		(at 406.107646 -22.171152 180)
		(property "Reference" "R25W79"
			(at -0.8382 -0.67818 180)
			(unlocked yes)
			(layer "F.SilkS")
			(effects
				(font
					(size 0.4064 0.254)
					(thickness 0.1524)
				)
				(justify left)
			)
		)
		(property "Value" ""
			(at 0 0 180)
			(layer "F.Fab")
			(effects
				(font
					(size 1.27 1.27)
				)
			)
		)
		(duplicate_pad_numbers_are_jumpers no)
		(fp_poly
			(pts
				(xy -0.2794 -0.1016) (xy 0.2794 -0.1016) (xy 0.2794 0.9906) (xy -0.2794 0.9906)
			)
			(stroke
				(width 0)
				(type default)
			)
			(fill no)
			(layer "F.CrtYd")
		)
		(fp_line
			(start 0.2794 0.9906)
			(end 0.2794 -0.1016)
			(stroke
				(width 0.1)
				(type default)
			)
			(layer "F.Fab")
		)
		(fp_line
			(start 0.2794 -0.1016)
			(end -0.2794 -0.1016)
			(stroke
				(width 0.1)
				(type default)
			)
			(layer "F.Fab")
		)
		(fp_line
			(start -0.2794 0.9906)
			(end 0.2794 0.9906)
			(stroke
				(width 0.1)
				(type default)
			)
			(layer "F.Fab")
		)
		(fp_line
			(start -0.2794 -0.1016)
			(end -0.2794 0.9906)
			(stroke
				(width 0.1)
				(type default)
			)
			(layer "F.Fab")
		)
		(pad "1" smd rect
			(at 0 0 180)
			(size 0.508 0.508)
			(layers "F.Cu" "F.Mask" "F.Paste")
			(net "P3V3_STBY")
		)
		(pad "2" smd rect
			(at 0 0.889 180)
			(size 0.508 0.508)
			(layers "F.Cu" "F.Mask" "F.Paste")
			(net "RMII_SPRNGVLLE_BMC_PCH_RXD0")
		)
		(zone
			(layer "F.Cu")
			(hatch none 0.5)
			(connect_pads
				(clearance 0)
			)
			(min_thickness 0.25)
			(keepout
				(tracks not_allowed)
				(vias allowed)
				(pads allowed)
				(copperpour not_allowed)
				(footprints allowed)
			)
			(placement
				(enabled no)
				(sheetname "")
			)
			(fill
				(thermal_gap 0.5)
				(thermal_bridge_width 0.5)
				(island_removal_mode 0)
			)
			(polygon
				(pts
					(xy 406.361646 -22.806152) (xy 405.853646 -22.806152) (xy 405.853646 -22.425152) (xy 406.361646 -22.425152)
				)
			)
		)
		(zone
			(layer "F.Cu")
			(hatch none 0.5)
			(connect_pads
				(clearance 0)
			)
			(min_thickness 0.25)
			(keepout
				(tracks allowed)
				(vias not_allowed)
				(pads allowed)
				(copperpour not_allowed)
				(footprints allowed)
			)
			(placement
				(enabled no)
				(sheetname "")
			)
			(fill
				(thermal_gap 0.5)
				(thermal_bridge_width 0.5)
				(island_removal_mode 0)
			)
			(polygon
				(pts
					(xy 406.361646 -22.425152) (xy 405.853646 -22.425152) (xy 405.853646 -22.806152) (xy 406.361646 -22.806152)
				)
			)
		)
	)
)
